# TIMECARD (Time Appliance Project (Time Card)) — schematic netlist excerpt (pin names and nets, part order shuffled) for the footprints in the layout excerpt that follows; sources: Cadence DE-HDL packaged netlist, KiCad conversion of R4006-B0001-02_R01.brd

C144  CAPACITOR  0.1UF 10V 10%  pkg SMC_0402R_H022  page 14 : \1\ = XP3R3V_FPGA ; \2\ = SG
R300  RESISTOR  4.7KOHM 1%  pkg SMC_0402R_H016  page 18 : \1\ = XP3R3V_FPGA ; \2\ = FPGA_IN_SHT3X_ALERT_N

(kicad_pcb
	(version 20260206)
	(generator "pcbnew")
	(generator_version "10.0")
	(general
		(thickness 1.6)
		(legacy_teardrops no)
	)
	(paper "A4")
	(title_block
		(title "timecard-production-celestica-r4006 — R4006-B0001-02_R01.brd")
		(comment 1 "Time Appliance Project (Time Card) / footprints 702-703 of 1113")
	)
	(layers
		(0 "F.Cu" signal "TOP")
		(4 "In1.Cu" signal "L02_GND1")
		(6 "In2.Cu" signal "L03_SIG1")
		(8 "In3.Cu" signal "L04_GND2")
		(10 "In4.Cu" signal "L05_VCC1")
		(12 "In5.Cu" signal "L06_VCC2")
		(14 "In6.Cu" signal "L07_GND3")
		(16 "In7.Cu" signal "L08_SIG2")
		(18 "In8.Cu" signal "L09_GND4")
		(2 "B.Cu" signal "BOTTOM")
		(9 "F.Adhes" user "F.Adhesive")
		(11 "B.Adhes" user "B.Adhesive")
		(13 "F.Paste" user "Package Geometry/Pastemask Top")
		(15 "B.Paste" user "Package Geometry/Pastemask Bottom")
		(5 "F.SilkS" user "Ref Des/Silkscreen Top")
		(7 "B.SilkS" user "Ref Des/Silkscreen Bottom")
		(1 "F.Mask" user "Board Geometry/Soldermask Top")
		(3 "B.Mask" user "Board Geometry/Soldermask Bottom")
		(17 "Dwgs.User" user "User.Drawings")
		(19 "Cmts.User" user "User.Comments")
		(21 "Eco1.User" user "User.Eco1")
		(23 "Eco2.User" user "User.Eco2")
		(25 "Edge.Cuts" user "Board Geometry/Outline")
		(27 "Margin" user)
		(31 "F.CrtYd" user "Package Geometry/Place Bound Top")
		(29 "B.CrtYd" user "Package Geometry/Place Bound Bottom")
		(35 "F.Fab" user "Ref Des/Assembly Top")
		(33 "B.Fab" user "Ref Des/Assembly Bottom")
	)
	(footprint ""
		(layer "B.Cu")
		(at 109.475524 -48.704246 -90)
		(property "Reference" "C144"
			(at -0.063754 -0.982726 270)
			(unlocked yes)
			(layer "B.SilkS")
			(effects
				(font
					(size 0.635 0.4064)
					(thickness 0.1524)
				)
				(justify mirror)
			)
		)
		(property "Value" "VAL*"
			(at 0 3.718306 270)
			(unlocked yes)
			(layer "B.Fab")
			(hide yes)
			(effects
				(font
					(size 0.7874 0.5842)
					(thickness 0.127)
				)
				(justify mirror)
			)
		)
		(property "Device Type" "CAPACITOR-G105-0B104-CK,0.1UF,A"
			(at 0 1.432306 270)
			(unlocked yes)
			(layer "B.Fab")
			(hide yes)
			(effects
				(font
					(size 0.7874 0.5842)
					(thickness 0.127)
				)
				(justify mirror)
			)
		)
		(property "User Part Number" "PARTNUM*"
			(at 0 2.575306 270)
			(unlocked yes)
			(layer "Cmts.User")
			(hide yes)
			(effects
				(font
					(size 0.7874 0.5842)
					(thickness 0.127)
				)
				(justify mirror)
			)
		)
		(property "Tolerance" "TOL*"
			(at 0 4.861306 270)
			(unlocked yes)
			(layer "Cmts.User")
			(hide yes)
			(effects
				(font
					(size 0.7874 0.5842)
					(thickness 0.127)
				)
				(justify mirror)
			)
		)
		(duplicate_pad_numbers_are_jumpers no)
		(fp_line
			(start -0.970026 0.4699)
			(end 0.970026 0.4699)
			(stroke
				(width 0.1)
				(type default)
			)
			(layer "B.SilkS")
		)
		(fp_line
			(start 0.970026 0.4699)
			(end 0.970026 -0.4699)
			(stroke
				(width 0.1)
				(type default)
			)
			(layer "B.SilkS")
		)
		(fp_line
			(start -0.970026 -0.4699)
			(end -0.970026 0.4699)
			(stroke
				(width 0.1)
				(type default)
			)
			(layer "B.SilkS")
		)
		(fp_line
			(start 0.970026 -0.4699)
			(end -0.970026 -0.4699)
			(stroke
				(width 0.1)
				(type default)
			)
			(layer "B.SilkS")
		)
		(fp_poly
			(pts
				(xy 0.970026 0.4699) (xy -0.970026 0.4699) (xy -0.970026 -0.4699) (xy 0.970026 -0.4699)
			)
			(stroke
				(width 0)
				(type default)
			)
			(fill no)
			(layer "B.CrtYd")
		)
		(fp_line
			(start -0.508 0.3048)
			(end 0.508 0.3048)
			(stroke
				(width 0.1)
				(type default)
			)
			(layer "B.Fab")
		)
		(fp_line
			(start 0.508 0.3048)
			(end 0.508 -0.3048)
			(stroke
				(width 0.1)
				(type default)
			)
			(layer "B.Fab")
		)
		(fp_line
			(start -0.508 -0.3048)
			(end -0.508 0.3048)
			(stroke
				(width 0.1)
				(type default)
			)
			(layer "B.Fab")
		)
		(fp_line
			(start 0.508 -0.3048)
			(end -0.508 -0.3048)
			(stroke
				(width 0.1)
				(type default)
			)
			(layer "B.Fab")
		)
		(pad "1" smd circle
			(at 0.500126 0 90)
			(size 0.635 0.635)
			(layers "B.Cu" "B.Mask" "B.Paste")
			(net "XP3R3V_FPGA")
		)
		(pad "2" smd circle
			(at -0.500126 0 90)
			(size 0.635 0.635)
			(layers "B.Cu" "B.Mask" "B.Paste")
			(net "SG")
		)
	)
	(footprint ""
		(layer "B.Cu")
		(at 152.883108 -49.01311 90)
		(property "Reference" "R300"
			(at 3.94589 -0.649478 270)
			(unlocked yes)
			(layer "B.SilkS")
			(effects
				(font
					(size 0.7874 0.5842)
					(thickness 0.1524)
				)
				(justify mirror)
			)
		)
		(property "Value" "VAL*"
			(at -0.02032 2.13233 90)
			(unlocked yes)
			(layer "B.Fab")
			(hide yes)
			(effects
				(font
					(size 0.7874 0.5842)
					(thickness 0.1524)
				)
				(justify mirror)
			)
		)
		(property "Device Type" "RESISTOR-G155-14701-01,4.7KOHMA"
			(at -0.008382 1.210564 90)
			(unlocked yes)
			(layer "B.Fab")
			(hide yes)
			(effects
				(font
					(size 0.7874 0.5842)
					(thickness 0.1524)
				)
				(justify mirror)
			)
		)
		(property "User Part Number" "PARTNUM*"
			(at -0.02032 4.024884 90)
			(unlocked yes)
			(layer "Cmts.User")
			(hide yes)
			(effects
				(font
					(size 0.7874 0.5842)
					(thickness 0.1524)
				)
				(justify mirror)
			)
		)
		(property "Tolerance" "TOL*"
			(at -0.044704 3.05435 90)
			(unlocked yes)
			(layer "Cmts.User")
			(hide yes)
			(effects
				(font
					(size 0.7874 0.5842)
					(thickness 0.1524)
				)
				(justify mirror)
			)
		)
		(duplicate_pad_numbers_are_jumpers no)
		(fp_line
			(start 1.143 -0.5588)
			(end 1.143 0.5588)
			(stroke
				(width 0.1)
				(type default)
			)
			(layer "B.SilkS")
		)
		(fp_line
			(start -1.143 -0.5588)
			(end 1.143 -0.5588)
			(stroke
				(width 0.1)
				(type default)
			)
			(layer "B.SilkS")
		)
		(fp_line
			(start 1.143 0.5588)
			(end -1.143 0.5588)
			(stroke
				(width 0.1)
				(type default)
			)
			(layer "B.SilkS")
		)
		(fp_line
			(start -1.143 0.5588)
			(end -1.143 -0.5588)
			(stroke
				(width 0.1)
				(type default)
			)
			(layer "B.SilkS")
		)
		(fp_rect
			(start 1.143 0.5588)
			(end -1.143 -0.5588)
			(stroke
				(width 0)
				(type default)
			)
			(fill no)
			(layer "B.CrtYd")
		)
		(fp_line
			(start 0.508 -0.3048)
			(end 0.508 0.3048)
			(stroke
				(width 0.1)
				(type default)
			)
			(layer "B.Fab")
		)
		(fp_line
			(start -0.508 -0.3048)
			(end 0.508 -0.3048)
			(stroke
				(width 0.1)
				(type default)
			)
			(layer "B.Fab")
		)
		(fp_line
			(start 0.508 0.3048)
			(end -0.508 0.3048)
			(stroke
				(width 0.1)
				(type default)
			)
			(layer "B.Fab")
		)
		(fp_line
			(start -0.508 0.3048)
			(end -0.508 -0.3048)
			(stroke
				(width 0.1)
				(type default)
			)
			(layer "B.Fab")
		)
		(pad "1" smd rect
			(at 0.5334 0 270)
			(size 0.7112 0.6096)
			(layers "B.Cu" "B.Mask" "B.Paste")
			(net "XP3R3V_FPGA")
		)
		(pad "2" smd rect
			(at -0.5334 0 270)
			(size 0.7112 0.6096)
			(layers "B.Cu" "B.Mask" "B.Paste")
			(net "FPGA_IN_SHT3X_ALERT_N")
		)
		(zone
			(layer "B.Cu")
			(hatch none 0.5)
			(connect_pads
				(clearance 0)
			)
			(min_thickness 0.25)
			(keepout
				(tracks allowed)
				(vias not_allowed)
				(pads allowed)
				(copperpour not_allowed)
				(footprints allowed)
			)
			(placement
				(enabled no)
				(sheetname "")
			)
			(fill
				(thermal_gap 0.5)
				(thermal_bridge_width 0.5)
				(island_removal_mode 0)
			)
			(polygon
				(pts
					(xy 153.187908 -49.08931) (xy 152.578308 -49.08931) (xy 152.578308 -48.93691) (xy 153.187908 -48.93691)
				)
			)
		)
	)
)
